# T6G (Grand Teton) — schematic netlist excerpt (pin names and nets, part order shuffled) for the footprints in the layout excerpt that follows; sources: Cadence DE-HDL packaged netlist, KiCad conversion of 04192023_DAF0TMB3IC0_F0TG_MB_C_brd_V02_OCP.brd

J45  CONN60_101062636003K02LF  CONN60_10106263-6003K02LF IO  pkg HSD_M60D4H2D_P2-54W2-54_LDHXB  page 240
  A1  = TP_J45_A1
  A2  = FM_AC_PWR_BTN_PDB_N
  A3  = P3V3_PDB_AUX_ADC
  B1  = RST_SMB_SWITCH_R_N
  B2  = PWRGD_P3V3_AUX_PDB_BUF
  B3  = GND
  C1  = SMB_FAN_3V3AUX_BUF_R_SCL
  C2  = SMB_FAN_3V3AUX_BUF_R_SDA
  C3  = HPDB_HSC_PWRGD_R
  D1  = FM_FAN_PWR_EN_R
  D2  = FM_GPU_HSC_EN_BUF_R1
  D3  = PDB_PRSNT_N
  P1_1  = GND
  P1_2  = GND
  P1_3  = GND
  P1_4  = GND
  P1_5  = GND
  P1_6  = GND
  P1_7  = GND
  P1_8  = GND
  P2_1  = GND
  P2_2  = GND
  P2_3  = GND
  P2_4  = GND
  P2_5  = GND
  P2_6  = GND
  P2_7  = GND
  P2_8  = GND
  P3_1  = GND
  P3_2  = GND
  P3_3  = GND
  P3_4  = GND
  P3_5  = GND
  P3_6  = GND
  P3_7  = GND
  P3_8  = GND
  P4_1  = P12V_PSU
  P4_2  = P12V_PSU
  P4_3  = P12V_PSU
  P4_4  = P12V_PSU
  P4_5  = P12V_PSU
  P4_6  = P12V_PSU
  P4_7  = P12V_PSU
  P4_8  = P12V_PSU
  P5_1  = P12V_PSU
  P5_2  = P12V_PSU
  P5_3  = P12V_PSU
  P5_4  = P12V_PSU
  P5_5  = P12V_PSU
  P5_6  = P12V_PSU
  P5_7  = P12V_PSU
  P5_8  = P12V_PSU
  P6_1  = P12V_PSU
  P6_2  = P12V_PSU
  P6_3  = P12V_PSU
  P6_4  = P12V_PSU
  P6_5  = P12V_PSU
  P6_6  = P12V_PSU
  P6_7  = P12V_PSU
  P6_8  = P12V_PSU

(kicad_pcb
	(version 20260206)
	(generator "pcbnew")
	(generator_version "10.0")
	(general
		(thickness 1.6)
		(legacy_teardrops no)
	)
	(paper "A4")
	(title_block
		(title "04192023_DAF0TMB3IC0_F0TG_MB_C_brd_V02_OCP.brd")
		(comment 1 "Grand Teton / footprint 1872 of 8354 (J45), pads 1-35 of 62")
	)
	(layers
		(0 "F.Cu" signal "TOP")
		(4 "In1.Cu" signal "GND")
		(6 "In2.Cu" signal "IN1")
		(8 "In3.Cu" signal "GND1")
		(10 "In4.Cu" signal "IN2")
		(12 "In5.Cu" signal "GND2")
		(14 "In6.Cu" signal "IN3")
		(16 "In7.Cu" signal "GND3")
		(18 "In8.Cu" signal "VCC")
		(20 "In9.Cu" signal "VCC1")
		(22 "In10.Cu" signal "GND4")
		(24 "In11.Cu" signal "IN4")
		(26 "In12.Cu" signal "GND5")
		(28 "In13.Cu" signal "IN5")
		(30 "In14.Cu" signal "GND6")
		(32 "In15.Cu" signal "IN6")
		(34 "In16.Cu" signal "GND7")
		(2 "B.Cu" signal "BOTTOM")
		(9 "F.Adhes" user "F.Adhesive")
		(11 "B.Adhes" user "B.Adhesive")
		(13 "F.Paste" user "Package Geometry/Pastemask Top")
		(15 "B.Paste" user "Package Geometry/Pastemask Bottom")
		(5 "F.SilkS" user "Ref Des/Silkscreen Top")
		(7 "B.SilkS" user "Ref Des/Silkscreen Bottom")
		(1 "F.Mask" user "Board Geometry/Soldermask Top")
		(3 "B.Mask" user "Board Geometry/Soldermask Bottom")
		(17 "Dwgs.User" user "User.Drawings")
		(19 "Cmts.User" user "User.Comments")
		(21 "Eco1.User" user "User.Eco1")
		(23 "Eco2.User" user "User.Eco2")
		(25 "Edge.Cuts" user "Board Geometry/Outline")
		(27 "Margin" user)
		(31 "F.CrtYd" user "Package Geometry/Place Bound Top")
		(29 "B.CrtYd" user "Package Geometry/Place Bound Bottom")
		(35 "F.Fab" user "Ref Des/Assembly Top")
		(33 "B.Fab" user "Ref Des/Assembly Bottom")
	)
	(footprint ""
		(layer "F.Cu")
		(at 238.45012 -435.58206 -90)
		(property "Reference" "J45"
			(at 11.30173 -38.15588 0)
			(unlocked yes)
			(layer "F.SilkS")
			(effects
				(font
					(size 0.7874 0.5842)
					(thickness 0.1524)
				)
				(justify left)
			)
		)
		(property "Value" ""
			(at 0 0 270)
			(layer "F.Fab")
			(effects
				(font
					(size 1.27 1.27)
				)
			)
		)
		(duplicate_pad_numbers_are_jumpers no)
		(pad "" np_thru_hole circle
			(at 2.54 -32.385 270)
			(size 0 0)
			(drill 3.048)
			(layers "*.Cu" "*.Mask")
			(clearance 0)
		)
		(pad "" np_thru_hole circle
			(at 2.54 37.465 270)
			(size 0 0)
			(drill 3.048)
			(layers "*.Cu" "*.Mask")
			(clearance 0)
		)
		(pad "A1" thru_hole rect
			(at 0 0 270)
			(size 1.669796 1.669796)
			(drill 1.01981)
			(layers "*.Cu" "*.Mask")
			(remove_unused_layers no)
			(net "TP_J45_A1")
			(clearance -0.070866)
			(padstack
				(mode front_inner_back)
				(layer "Inner"
					(shape circle)
					(size 1.669796 1.669796)
					(clearance -0.070866)
				)
				(layer "B.Cu"
					(shape rect)
					(size 1.669796 1.669796)
					(clearance -0.070866)
				)
			)
		)
		(pad "A2" thru_hole circle
			(at 0 2.54 270)
			(size 1.669796 1.669796)
			(drill 1.01981)
			(layers "*.Cu" "*.Mask")
			(remove_unused_layers no)
			(net "FM_AC_PWR_BTN_PDB_N")
			(clearance -0.070866)
		)
		(pad "A3" thru_hole circle
			(at 0 5.08 270)
			(size 1.669796 1.669796)
			(drill 1.01981)
			(layers "*.Cu" "*.Mask")
			(remove_unused_layers no)
			(net "P3V3_PDB_AUX_ADC")
			(clearance -0.070866)
		)
		(pad "B1" thru_hole circle
			(at 2.54 0 270)
			(size 1.669796 1.669796)
			(drill 1.01981)
			(layers "*.Cu" "*.Mask")
			(remove_unused_layers no)
			(net "RST_SMB_SWITCH_R_N")
			(clearance -0.070866)
		)
		(pad "B2" thru_hole circle
			(at 2.54 2.54 270)
			(size 1.669796 1.669796)
			(drill 1.01981)
			(layers "*.Cu" "*.Mask")
			(remove_unused_layers no)
			(net "PWRGD_P3V3_AUX_PDB_BUF")
			(clearance -0.070866)
		)
		(pad "B3" thru_hole circle
			(at 2.54 5.08 270)
			(size 1.669796 1.669796)
			(drill 1.01981)
			(layers "*.Cu" "*.Mask")
			(remove_unused_layers no)
			(net "GND")
			(clearance -0.070866)
		)
		(pad "C1" thru_hole circle
			(at 5.08 0 270)
			(size 1.669796 1.669796)
			(drill 1.01981)
			(layers "*.Cu" "*.Mask")
			(remove_unused_layers no)
			(net "SMB_FAN_3V3AUX_BUF_R_SCL")
			(clearance -0.070866)
		)
		(pad "C2" thru_hole circle
			(at 5.08 2.54 270)
			(size 1.669796 1.669796)
			(drill 1.01981)
			(layers "*.Cu" "*.Mask")
			(remove_unused_layers no)
			(net "SMB_FAN_3V3AUX_BUF_R_SDA")
			(clearance -0.070866)
		)
		(pad "C3" thru_hole circle
			(at 5.08 5.08 270)
			(size 1.669796 1.669796)
			(drill 1.01981)
			(layers "*.Cu" "*.Mask")
			(remove_unused_layers no)
			(net "HPDB_HSC_PWRGD_R")
			(clearance -0.070866)
		)
		(pad "D1" thru_hole circle
			(at 7.62 0 270)
			(size 1.669796 1.669796)
			(drill 1.01981)
			(layers "*.Cu" "*.Mask")
			(remove_unused_layers no)
			(net "FM_FAN_PWR_EN_R")
			(clearance -0.070866)
		)
		(pad "D2" thru_hole circle
			(at 7.62 2.54 270)
			(size 1.669796 1.669796)
			(drill 1.01981)
			(layers "*.Cu" "*.Mask")
			(remove_unused_layers no)
			(net "FM_GPU_HSC_EN_BUF_R1")
			(clearance -0.070866)
		)
		(pad "D3" thru_hole circle
			(at 7.62 5.08 270)
			(size 1.669796 1.669796)
			(drill 1.01981)
			(layers "*.Cu" "*.Mask")
			(remove_unused_layers no)
			(net "PDB_PRSNT_N")
			(clearance -0.070866)
		)
		(pad "P1_1" thru_hole circle
			(at 0 -25.4 270)
			(size 1.669796 1.669796)
			(drill 1.01981)
			(layers "*.Cu" "*.Mask")
			(remove_unused_layers no)
			(net "GND")
			(clearance -0.070866)
		)
		(pad "P1_2" thru_hole circle
			(at 2.54 -25.4 270)
			(size 1.669796 1.669796)
			(drill 1.01981)
			(layers "*.Cu" "*.Mask")
			(remove_unused_layers no)
			(net "GND")
			(clearance -0.070866)
		)
		(pad "P1_3" thru_hole circle
			(at 5.08 -25.4 270)
			(size 1.669796 1.669796)
			(drill 1.01981)
			(layers "*.Cu" "*.Mask")
			(remove_unused_layers no)
			(net "GND")
			(clearance -0.070866)
		)
		(pad "P1_4" thru_hole circle
			(at 7.62 -25.4 270)
			(size 1.669796 1.669796)
			(drill 1.01981)
			(layers "*.Cu" "*.Mask")
			(remove_unused_layers no)
			(net "GND")
			(clearance -0.070866)
		)
		(pad "P1_5" thru_hole circle
			(at 0 -22.86 270)
			(size 1.669796 1.669796)
			(drill 1.01981)
			(layers "*.Cu" "*.Mask")
			(remove_unused_layers no)
			(net "GND")
			(clearance -0.070866)
		)
		(pad "P1_6" thru_hole circle
			(at 2.54 -22.86 270)
			(size 1.669796 1.669796)
			(drill 1.01981)
			(layers "*.Cu" "*.Mask")
			(remove_unused_layers no)
			(net "GND")
			(clearance -0.070866)
		)
		(pad "P1_7" thru_hole circle
			(at 5.08 -22.86 270)
			(size 1.669796 1.669796)
			(drill 1.01981)
			(layers "*.Cu" "*.Mask")
			(remove_unused_layers no)
			(net "GND")
			(clearance -0.070866)
		)
		(pad "P1_8" thru_hole circle
			(at 7.62 -22.86 270)
			(size 1.669796 1.669796)
			(drill 1.01981)
			(layers "*.Cu" "*.Mask")
			(remove_unused_layers no)
			(net "GND")
			(clearance -0.070866)
		)
		(pad "P2_1" thru_hole circle
			(at 0 -16.51 270)
			(size 1.669796 1.669796)
			(drill 1.01981)
			(layers "*.Cu" "*.Mask")
			(remove_unused_layers no)
			(net "GND")
			(clearance -0.070866)
		)
		(pad "P2_2" thru_hole circle
			(at 2.54 -16.51 270)
			(size 1.669796 1.669796)
			(drill 1.01981)
			(layers "*.Cu" "*.Mask")
			(remove_unused_layers no)
			(net "GND")
			(clearance -0.070866)
		)
		(pad "P2_3" thru_hole circle
			(at 5.08 -16.51 270)
			(size 1.669796 1.669796)
			(drill 1.01981)
			(layers "*.Cu" "*.Mask")
			(remove_unused_layers no)
			(net "GND")
			(clearance -0.070866)
		)
		(pad "P2_4" thru_hole circle
			(at 7.62 -16.51 270)
			(size 1.669796 1.669796)
			(drill 1.01981)
			(layers "*.Cu" "*.Mask")
			(remove_unused_layers no)
			(net "GND")
			(clearance -0.070866)
		)
		(pad "P2_5" thru_hole circle
			(at 0 -13.97 270)
			(size 1.669796 1.669796)
			(drill 1.01981)
			(layers "*.Cu" "*.Mask")
			(remove_unused_layers no)
			(net "GND")
			(clearance -0.070866)
		)
		(pad "P2_6" thru_hole circle
			(at 2.54 -13.97 270)
			(size 1.669796 1.669796)
			(drill 1.01981)
			(layers "*.Cu" "*.Mask")
			(remove_unused_layers no)
			(net "GND")
			(clearance -0.070866)
		)
		(pad "P2_7" thru_hole circle
			(at 5.08 -13.97 270)
			(size 1.669796 1.669796)
			(drill 1.01981)
			(layers "*.Cu" "*.Mask")
			(remove_unused_layers no)
			(net "GND")
			(clearance -0.070866)
		)
		(pad "P2_8" thru_hole circle
			(at 7.62 -13.97 270)
			(size 1.669796 1.669796)
			(drill 1.01981)
			(layers "*.Cu" "*.Mask")
			(remove_unused_layers no)
			(net "GND")
			(clearance -0.070866)
		)
		(pad "P3_1" thru_hole circle
			(at 0 -7.62 270)
			(size 1.669796 1.669796)
			(drill 1.01981)
			(layers "*.Cu" "*.Mask")
			(remove_unused_layers no)
			(net "GND")
			(clearance -0.070866)
		)
		(pad "P3_2" thru_hole circle
			(at 2.54 -7.62 270)
			(size 1.669796 1.669796)
			(drill 1.01981)
			(layers "*.Cu" "*.Mask")
			(remove_unused_layers no)
			(net "GND")
			(clearance -0.070866)
		)
		(pad "P3_3" thru_hole circle
			(at 5.08 -7.62 270)
			(size 1.669796 1.669796)
			(drill 1.01981)
			(layers "*.Cu" "*.Mask")
			(remove_unused_layers no)
			(net "GND")
			(clearance -0.070866)
		)
		(pad "P3_4" thru_hole circle
			(at 7.62 -7.62 270)
			(size 1.669796 1.669796)
			(drill 1.01981)
			(layers "*.Cu" "*.Mask")
			(remove_unused_layers no)
			(net "GND")
			(clearance -0.070866)
		)
		(pad "P3_5" thru_hole circle
			(at 0 -5.08 270)
			(size 1.669796 1.669796)
			(drill 1.01981)
			(layers "*.Cu" "*.Mask")
			(remove_unused_layers no)
			(net "GND")
			(clearance -0.070866)
		)
	)
)
